(kicad_pcb
	(version 20260206)
	(generator "pcbnew")
	(generator_version "10.0")
	(general
		(thickness 1.6)
		(legacy_teardrops no)
	)
	(paper "A4")
	(title_block
		(title "03242023_DA0F0TMBIJ0_F0T_Motherboard_J_brd_V01_OCP.brd")
		(comment 1 "Grand Teton / footprints 3430-3430 of 6105")
	)
	(layers
		(0 "F.Cu" signal "TOP")
		(4 "In1.Cu" signal "GND")
		(6 "In2.Cu" signal "IN1")
		(8 "In3.Cu" signal "GND1")
		(10 "In4.Cu" signal "IN2")
		(12 "In5.Cu" signal "GND2")
		(14 "In6.Cu" signal "IN3")
		(16 "In7.Cu" signal "GND3")
		(18 "In8.Cu" signal "VCC")
		(20 "In9.Cu" signal "VCC1")
		(22 "In10.Cu" signal "GND4")
		(24 "In11.Cu" signal "IN4")
		(26 "In12.Cu" signal "GND5")
		(28 "In13.Cu" signal "IN5")
		(30 "In14.Cu" signal "GND6")
		(32 "In15.Cu" signal "IN6")
		(34 "In16.Cu" signal "GND7")
		(2 "B.Cu" signal "BOTTOM")
		(9 "F.Adhes" user "F.Adhesive")
		(11 "B.Adhes" user "B.Adhesive")
		(13 "F.Paste" user "Package Geometry/Pastemask Top")
		(15 "B.Paste" user "Package Geometry/Pastemask Bottom")
		(5 "F.SilkS" user "Ref Des/Silkscreen Top")
		(7 "B.SilkS" user "Ref Des/Silkscreen Bottom")
		(1 "F.Mask" user "Board Geometry/Soldermask Top")
		(3 "B.Mask" user "Board Geometry/Soldermask Bottom")
		(17 "Dwgs.User" user "User.Drawings")
		(19 "Cmts.User" user "User.Comments")
		(21 "Eco1.User" user "User.Eco1")
		(23 "Eco2.User" user "User.Eco2")
		(25 "Edge.Cuts" user "Board Geometry/Outline")
		(27 "Margin" user)
		(31 "F.CrtYd" user "Package Geometry/Place Bound Top")
		(29 "B.CrtYd" user "Package Geometry/Place Bound Bottom")
		(35 "F.Fab" user "Ref Des/Assembly Top")
		(33 "B.Fab" user "Ref Des/Assembly Bottom")
	)
	(footprint ""
		(layer "F.Cu")
		(at 113.873534 -38.065456)
		(property "Reference" "R3327"
			(at 0 0 0)
			(layer "F.SilkS")
			(hide yes)
			(effects
				(font
					(size 1.27 1.27)
				)
			)
		)
		(property "Value" ""
			(at 0 0 0)
			(layer "F.Fab")
			(effects
				(font
					(size 1.27 1.27)
				)
			)
		)
		(duplicate_pad_numbers_are_jumpers no)
		(fp_line
			(start -0.7874 -0.4064)
			(end 0.7874 -0.4064)
			(stroke
				(width 0.1524)
				(type default)
			)
			(layer "F.SilkS")
		)
		(fp_line
			(start -0.7874 0.4064)
			(end -0.7874 -0.4064)
			(stroke
				(width 0.1524)
				(type default)
			)
			(layer "F.SilkS")
		)
		(fp_line
			(start 0.7874 -0.4064)
			(end 0.7874 0.4064)
			(stroke
				(width 0.1524)
				(type default)
			)
			(layer "F.SilkS")
		)
		(fp_line
			(start 0.7874 0.4064)
			(end -0.7874 0.4064)
			(stroke
				(width 0.1524)
				(type default)
			)
			(layer "F.SilkS")
		)
		(fp_line
			(start -0.67945 -0.305054)
			(end -0.12065 -0.305054)
			(stroke
				(width 0.1)
				(type default)
			)
			(layer "F.Fab")
		)
		(fp_line
			(start -0.67945 0.3048)
			(end -0.67945 -0.305054)
			(stroke
				(width 0.1)
				(type default)
			)
			(layer "F.Fab")
		)
		(fp_line
			(start -0.12065 -0.305054)
			(end -0.12065 -0.2794)
			(stroke
				(width 0.1)
				(type default)
			)
			(layer "F.Fab")
		)
		(fp_line
			(start -0.12065 -0.2794)
			(end 0.12065 -0.2794)
			(stroke
				(width 0.1)
				(type default)
			)
			(layer "F.Fab")
		)
		(fp_line
			(start -0.12065 0.2794)
			(end -0.12065 0.3048)
			(stroke
				(width 0.1)
				(type default)
			)
			(layer "F.Fab")
		)
		(fp_line
			(start -0.12065 0.3048)
			(end -0.67945 0.3048)
			(stroke
				(width 0.1)
				(type default)
			)
			(layer "F.Fab")
		)
		(fp_line
			(start 0.120396 0.2794)
			(end -0.12065 0.2794)
			(stroke
				(width 0.1)
				(type default)
			)
			(layer "F.Fab")
		)
		(fp_line
			(start 0.120396 0.3048)
			(end 0.120396 0.2794)
			(stroke
				(width 0.1)
				(type default)
			)
			(layer "F.Fab")
		)
		(fp_line
			(start 0.12065 -0.3048)
			(end 0.67945 -0.3048)
			(stroke
				(width 0.1)
				(type default)
			)
			(layer "F.Fab")
		)
		(fp_line
			(start 0.12065 -0.2794)
			(end 0.12065 -0.3048)
			(stroke
				(width 0.1)
				(type default)
			)
			(layer "F.Fab")
		)
		(fp_line
			(start 0.67945 -0.3048)
			(end 0.67945 0.3048)
			(stroke
				(width 0.1)
				(type default)
			)
			(layer "F.Fab")
		)
		(fp_line
			(start 0.67945 0.3048)
			(end 0.120396 0.3048)
			(stroke
				(width 0.1)
				(type default)
			)
			(layer "F.Fab")
		)
		(pad "1" smd circle
			(at -0.40005 0)
			(size 0 0)
			(layers "F.Cu" "F.Mask" "F.Paste")
			(net "CLK_GEN2_GPU_FPGA_OE_N")
		)
		(pad "2" smd circle
			(at 0.40005 0)
			(size 0 0)
			(layers "F.Cu" "F.Mask" "F.Paste")
			(net "CLK_GEN2_GPU_FPGA_OE_R2_N")
		)
	)
)
